# T6G (Grand Teton) — schematic netlist excerpt (pin names and nets, part order shuffled) for the footprints in the layout excerpt that follows; sources: Cadence DE-HDL packaged netlist, KiCad conversion of 04192023_DAF0TMB3IC0_F0TG_MB_C_brd_V02_OCP.brd

J74  PICOPROBE_BXA  DELTA-L 4.0 EMPTY  pkg TRIANG_LAUNCH_3PXB  page 229
  \1_p\  = DELTA_L_85_5INCH_IN4_DN
  \2_n\  = DELTA_L_85_5INCH_IN4_DP
  \3_g\  = DELTA_L_GND_1

(kicad_pcb
	(version 20260206)
	(generator "pcbnew")
	(generator_version "10.0")
	(general
		(thickness 1.6)
		(legacy_teardrops no)
	)
	(paper "A4")
	(title_block
		(title "04192023_DAF0TMB3IC0_F0TG_MB_C_brd_V02_OCP.brd")
		(comment 1 "Grand Teton / footprints 6424-6424 of 8354")
	)
	(layers
		(0 "F.Cu" signal "TOP")
		(4 "In1.Cu" signal "GND")
		(6 "In2.Cu" signal "IN1")
		(8 "In3.Cu" signal "GND1")
		(10 "In4.Cu" signal "IN2")
		(12 "In5.Cu" signal "GND2")
		(14 "In6.Cu" signal "IN3")
		(16 "In7.Cu" signal "GND3")
		(18 "In8.Cu" signal "VCC")
		(20 "In9.Cu" signal "VCC1")
		(22 "In10.Cu" signal "GND4")
		(24 "In11.Cu" signal "IN4")
		(26 "In12.Cu" signal "GND5")
		(28 "In13.Cu" signal "IN5")
		(30 "In14.Cu" signal "GND6")
		(32 "In15.Cu" signal "IN6")
		(34 "In16.Cu" signal "GND7")
		(2 "B.Cu" signal "BOTTOM")
		(9 "F.Adhes" user "F.Adhesive")
		(11 "B.Adhes" user "B.Adhesive")
		(13 "F.Paste" user "Package Geometry/Pastemask Top")
		(15 "B.Paste" user "Package Geometry/Pastemask Bottom")
		(5 "F.SilkS" user "Ref Des/Silkscreen Top")
		(7 "B.SilkS" user "Ref Des/Silkscreen Bottom")
		(1 "F.Mask" user "Board Geometry/Soldermask Top")
		(3 "B.Mask" user "Board Geometry/Soldermask Bottom")
		(17 "Dwgs.User" user "User.Drawings")
		(19 "Cmts.User" user "User.Comments")
		(21 "Eco1.User" user "User.Eco1")
		(23 "Eco2.User" user "User.Eco2")
		(25 "Edge.Cuts" user "Board Geometry/Outline")
		(27 "Margin" user)
		(31 "F.CrtYd" user "Package Geometry/Place Bound Top")
		(29 "B.CrtYd" user "Package Geometry/Place Bound Bottom")
		(35 "F.Fab" user "Ref Des/Assembly Top")
		(33 "B.Fab" user "Ref Des/Assembly Bottom")
	)
	(footprint ""
		(layer "B.Cu")
		(at 389.462264 8.689848 180)
		(property "Reference" "J74"
			(at 4.491482 -1.033526 270)
			(unlocked yes)
			(layer "B.SilkS")
			(effects
				(font
					(size 0.7874 0.5842)
					(thickness 0.1524)
				)
				(justify left mirror)
			)
		)
		(property "Value" ""
			(at 0 0 0)
			(layer "B.Fab")
			(effects
				(font
					(size 1.27 1.27)
				)
				(justify mirror)
			)
		)
		(duplicate_pad_numbers_are_jumpers no)
		(fp_line
			(start 1.2192 2.06756)
			(end 1.2192 -2.06756)
			(stroke
				(width 0.1524)
				(type default)
			)
			(layer "B.SilkS")
		)
		(fp_line
			(start 1.2192 -2.06756)
			(end -1.2192 -2.06756)
			(stroke
				(width 0.1524)
				(type default)
			)
			(layer "B.SilkS")
		)
		(fp_line
			(start -1.2192 2.06756)
			(end 1.2192 2.06756)
			(stroke
				(width 0.1524)
				(type default)
			)
			(layer "B.SilkS")
		)
		(fp_line
			(start -1.2192 -2.06756)
			(end -1.2192 2.06756)
			(stroke
				(width 0.1524)
				(type default)
			)
			(layer "B.SilkS")
		)
		(pad "" np_thru_hole circle
			(at -3.4671 -1.27 90)
			(size 1.0414 1.0414)
			(drill 1.0414)
			(layers "*.Cu" "*.Mask")
			(clearance 0.381)
			(thermal_gap 0.381)
		)
		(pad "" np_thru_hole circle
			(at -3.4671 1.27 90)
			(size 1.0414 1.0414)
			(drill 1.0414)
			(layers "*.Cu" "*.Mask")
			(clearance 0.381)
			(thermal_gap 0.381)
		)
		(pad "" np_thru_hole circle
			(at 2.8829 -1.27 90)
			(size 1.0414 1.0414)
			(drill 1.0414)
			(layers "*.Cu" "*.Mask")
			(clearance 0.381)
			(thermal_gap 0.381)
		)
		(pad "" np_thru_hole circle
			(at 2.8829 1.27 90)
			(size 1.0414 1.0414)
			(drill 1.0414)
			(layers "*.Cu" "*.Mask")
			(clearance 0.381)
			(thermal_gap 0.381)
		)
		(pad "1" smd rect
			(at -0.8255 -0.249936 90)
			(size 0.3048 0.508)
			(layers "B.Cu" "B.Mask" "B.Paste")
			(net "DELTA_L_85_5INCH_IN4_DN")
		)
		(pad "2" smd rect
			(at -0.8255 0.249936 90)
			(size 0.3048 0.508)
			(layers "B.Cu" "B.Mask" "B.Paste")
			(net "DELTA_L_85_5INCH_IN4_DP")
		)
		(pad "3" smd circle
			(at 0 0)
			(size 0 0)
			(layers "B.Cu" "B.Mask" "B.Paste")
			(net "DELTA_L_GND_1")
		)
		(zone
			(layers "F.Cu" "B.Cu" "In1.Cu" "In2.Cu" "In3.Cu" "In4.Cu" "In5.Cu" "In6.Cu"
				"In7.Cu" "In8.Cu" "In9.Cu" "In10.Cu" "In11.Cu" "In12.Cu" "In13.Cu" "In14.Cu"
				"In15.Cu" "In16.Cu"
			)
			(hatch none 0.5)
			(connect_pads
				(clearance 0)
			)
			(min_thickness 0.25)
			(keepout
				(tracks not_allowed)
				(vias allowed)
				(pads allowed)
				(copperpour not_allowed)
				(footprints allowed)
			)
			(placement
				(enabled no)
				(sheetname "")
			)
			(fill
				(thermal_gap 0.5)
				(thermal_bridge_width 0.5)
				(island_removal_mode 0)
			)
			(polygon
				(pts
					(arc
						(start 387.506464 7.419848)
						(mid 385.652264 7.419848)
						(end 387.506464 7.419848)
					)
				)
			)
		)
		(zone
			(layers "F.Cu" "B.Cu" "In1.Cu" "In2.Cu" "In3.Cu" "In4.Cu" "In5.Cu" "In6.Cu"
				"In7.Cu" "In8.Cu" "In9.Cu" "In10.Cu" "In11.Cu" "In12.Cu" "In13.Cu" "In14.Cu"
				"In15.Cu" "In16.Cu"
			)
			(hatch none 0.5)
			(connect_pads
				(clearance 0)
			)
			(min_thickness 0.25)
			(keepout
				(tracks not_allowed)
				(vias allowed)
				(pads allowed)
				(copperpour not_allowed)
				(footprints allowed)
			)
			(placement
				(enabled no)
				(sheetname "")
			)
			(fill
				(thermal_gap 0.5)
				(thermal_bridge_width 0.5)
				(island_removal_mode 0)
			)
			(polygon
				(pts
					(arc
						(start 387.506464 9.959848)
						(mid 385.652264 9.959848)
						(end 387.506464 9.959848)
					)
				)
			)
		)
		(zone
			(layers "F.Cu" "B.Cu" "In1.Cu" "In2.Cu" "In3.Cu" "In4.Cu" "In5.Cu" "In6.Cu"
				"In7.Cu" "In8.Cu" "In9.Cu" "In10.Cu" "In11.Cu" "In12.Cu" "In13.Cu" "In14.Cu"
				"In15.Cu" "In16.Cu"
			)
			(hatch none 0.5)
			(connect_pads
				(clearance 0)
			)
			(min_thickness 0.25)
			(keepout
				(tracks not_allowed)
				(vias allowed)
				(pads allowed)
				(copperpour not_allowed)
				(footprints allowed)
			)
			(placement
				(enabled no)
				(sheetname "")
			)
			(fill
				(thermal_gap 0.5)
				(thermal_bridge_width 0.5)
				(island_removal_mode 0)
			)
			(polygon
				(pts
					(arc
						(start 393.856464 7.419848)
						(mid 392.002264 7.419848)
						(end 393.856464 7.419848)
					)
				)
			)
		)
		(zone
			(layers "F.Cu" "B.Cu" "In1.Cu" "In2.Cu" "In3.Cu" "In4.Cu" "In5.Cu" "In6.Cu"
				"In7.Cu" "In8.Cu" "In9.Cu" "In10.Cu" "In11.Cu" "In12.Cu" "In13.Cu" "In14.Cu"
				"In15.Cu" "In16.Cu"
			)
			(hatch none 0.5)
			(connect_pads
				(clearance 0)
			)
			(min_thickness 0.25)
			(keepout
				(tracks not_allowed)
				(vias allowed)
				(pads allowed)
				(copperpour not_allowed)
				(footprints allowed)
			)
			(placement
				(enabled no)
				(sheetname "")
			)
			(fill
				(thermal_gap 0.5)
				(thermal_bridge_width 0.5)
				(island_removal_mode 0)
			)
			(polygon
				(pts
					(arc
						(start 393.856464 9.959848)
						(mid 392.002264 9.959848)
						(end 393.856464 9.959848)
					)
				)
			)
		)
		(zone
			(layer "B.Cu")
			(hatch none 0.5)
			(connect_pads
				(clearance 0)
			)
			(min_thickness 0.25)
			(keepout
				(tracks not_allowed)
				(vias allowed)
				(pads allowed)
				(copperpour not_allowed)
				(footprints allowed)
			)
			(placement
				(enabled no)
				(sheetname "")
			)
			(fill
				(thermal_gap 0.5)
				(thermal_bridge_width 0.5)
				(island_removal_mode 0)
			)
			(polygon
				(pts
					(xy 390.579864 9.238488) (xy 390.579864 9.142984) (xy 389.982964 9.142984) (xy 389.982964 8.736584)
					(xy 390.579864 8.736584) (xy 390.579864 8.643112) (xy 389.982964 8.643112) (xy 389.982964 8.236712)
					(xy 390.579864 8.236712) (xy 390.579864 8.141208) (xy 389.881364 8.141208) (xy 389.881364 9.238488)
				)
			)
		)
	)
)
